(kicad_pcb
	(version 20260206)
	(generator "pcbnew")
	(generator_version "10.0")
	(general
		(thickness 1.6)
		(legacy_teardrops no)
	)
	(paper "A4")
	(title_block
		(title "04192023_DAF0TMB3IC0_F0TG_MB_C_brd_V02_OCP.brd")
		(comment 1 "Grand Teton / footprints 294-300 of 8354")
	)
	(layers
		(0 "F.Cu" signal "TOP")
		(4 "In1.Cu" signal "GND")
		(6 "In2.Cu" signal "IN1")
		(8 "In3.Cu" signal "GND1")
		(10 "In4.Cu" signal "IN2")
		(12 "In5.Cu" signal "GND2")
		(14 "In6.Cu" signal "IN3")
		(16 "In7.Cu" signal "GND3")
		(18 "In8.Cu" signal "VCC")
		(20 "In9.Cu" signal "VCC1")
		(22 "In10.Cu" signal "GND4")
		(24 "In11.Cu" signal "IN4")
		(26 "In12.Cu" signal "GND5")
		(28 "In13.Cu" signal "IN5")
		(30 "In14.Cu" signal "GND6")
		(32 "In15.Cu" signal "IN6")
		(34 "In16.Cu" signal "GND7")
		(2 "B.Cu" signal "BOTTOM")
		(9 "F.Adhes" user "F.Adhesive")
		(11 "B.Adhes" user "B.Adhesive")
		(13 "F.Paste" user "Package Geometry/Pastemask Top")
		(15 "B.Paste" user "Package Geometry/Pastemask Bottom")
		(5 "F.SilkS" user "Ref Des/Silkscreen Top")
		(7 "B.SilkS" user "Ref Des/Silkscreen Bottom")
		(1 "F.Mask" user "Board Geometry/Soldermask Top")
		(3 "B.Mask" user "Board Geometry/Soldermask Bottom")
		(17 "Dwgs.User" user "User.Drawings")
		(19 "Cmts.User" user "User.Comments")
		(21 "Eco1.User" user "User.Eco1")
		(23 "Eco2.User" user "User.Eco2")
		(25 "Edge.Cuts" user "Board Geometry/Outline")
		(27 "Margin" user)
		(31 "F.CrtYd" user "Package Geometry/Place Bound Top")
		(29 "B.CrtYd" user "Package Geometry/Place Bound Bottom")
		(35 "F.Fab" user "Ref Des/Assembly Top")
		(33 "B.Fab" user "Ref Des/Assembly Bottom")
	)
	(footprint ""
		(layer "F.Cu")
		(at 393.148058 -177.04562 90)
		(property "Reference" "PC583_1"
			(at 0 0 90)
			(layer "F.SilkS")
			(hide yes)
			(effects
				(font
					(size 1.27 1.27)
				)
			)
		)
		(property "Value" ""
			(at 0 0 90)
			(layer "F.Fab")
			(effects
				(font
					(size 1.27 1.27)
				)
			)
		)
		(duplicate_pad_numbers_are_jumpers no)
		(fp_line
			(start 0.7874 -0.4064)
			(end 0.7874 0.4064)
			(stroke
				(width 0.1524)
				(type default)
			)
			(layer "F.SilkS")
		)
		(fp_line
			(start -0.7874 -0.4064)
			(end 0.7874 -0.4064)
			(stroke
				(width 0.1524)
				(type default)
			)
			(layer "F.SilkS")
		)
		(fp_line
			(start 0.7874 0.4064)
			(end -0.7874 0.4064)
			(stroke
				(width 0.1524)
				(type default)
			)
			(layer "F.SilkS")
		)
		(fp_line
			(start -0.7874 0.4064)
			(end -0.7874 -0.4064)
			(stroke
				(width 0.1524)
				(type default)
			)
			(layer "F.SilkS")
		)
		(fp_line
			(start -0.12065 -0.305054)
			(end -0.12065 -0.2794)
			(stroke
				(width 0.1)
				(type default)
			)
			(layer "F.Fab")
		)
		(fp_line
			(start -0.67945 -0.305054)
			(end -0.12065 -0.305054)
			(stroke
				(width 0.1)
				(type default)
			)
			(layer "F.Fab")
		)
		(fp_line
			(start 0.67945 -0.3048)
			(end 0.67945 0.3048)
			(stroke
				(width 0.1)
				(type default)
			)
			(layer "F.Fab")
		)
		(fp_line
			(start 0.12065 -0.3048)
			(end 0.67945 -0.3048)
			(stroke
				(width 0.1)
				(type default)
			)
			(layer "F.Fab")
		)
		(fp_line
			(start 0.12065 -0.2794)
			(end 0.12065 -0.3048)
			(stroke
				(width 0.1)
				(type default)
			)
			(layer "F.Fab")
		)
		(fp_line
			(start -0.12065 -0.2794)
			(end 0.12065 -0.2794)
			(stroke
				(width 0.1)
				(type default)
			)
			(layer "F.Fab")
		)
		(fp_line
			(start 0.120396 0.2794)
			(end -0.12065 0.2794)
			(stroke
				(width 0.1)
				(type default)
			)
			(layer "F.Fab")
		)
		(fp_line
			(start -0.12065 0.2794)
			(end -0.12065 0.3048)
			(stroke
				(width 0.1)
				(type default)
			)
			(layer "F.Fab")
		)
		(fp_line
			(start 0.67945 0.3048)
			(end 0.120396 0.3048)
			(stroke
				(width 0.1)
				(type default)
			)
			(layer "F.Fab")
		)
		(fp_line
			(start 0.120396 0.3048)
			(end 0.120396 0.2794)
			(stroke
				(width 0.1)
				(type default)
			)
			(layer "F.Fab")
		)
		(fp_line
			(start -0.12065 0.3048)
			(end -0.67945 0.3048)
			(stroke
				(width 0.1)
				(type default)
			)
			(layer "F.Fab")
		)
		(fp_line
			(start -0.67945 0.3048)
			(end -0.67945 -0.305054)
			(stroke
				(width 0.1)
				(type default)
			)
			(layer "F.Fab")
		)
		(pad "1" smd circle
			(at -0.40005 0 90)
			(size 0 0)
			(layers "F.Cu" "F.Mask" "F.Paste")
			(net "SW_P12V_AUX_PVDDCR_SOC_P0_FLT")
		)
		(pad "2" smd circle
			(at 0.40005 0 90)
			(size 0 0)
			(layers "F.Cu" "F.Mask" "F.Paste")
			(net "GND")
		)
	)
	(footprint ""
		(layer "F.Cu")
		(at 136.531096 -370.57203 -90)
		(property "Reference" "C52"
			(at 0 0 270)
			(layer "F.SilkS")
			(hide yes)
			(effects
				(font
					(size 1.27 1.27)
				)
			)
		)
		(property "Value" ""
			(at 0 0 270)
			(layer "F.Fab")
			(effects
				(font
					(size 1.27 1.27)
				)
			)
		)
		(duplicate_pad_numbers_are_jumpers no)
		(fp_line
			(start -0.299974 0.150114)
			(end -0.299974 -0.150114)
			(stroke
				(width 0.1)
				(type default)
			)
			(layer "F.Fab")
		)
		(fp_line
			(start 0.299974 0.150114)
			(end -0.299974 0.150114)
			(stroke
				(width 0.1)
				(type default)
			)
			(layer "F.Fab")
		)
		(fp_line
			(start -0.299974 -0.150114)
			(end 0.299974 -0.150114)
			(stroke
				(width 0.1)
				(type default)
			)
			(layer "F.Fab")
		)
		(fp_line
			(start 0.299974 -0.150114)
			(end 0.299974 0.150114)
			(stroke
				(width 0.1)
				(type default)
			)
			(layer "F.Fab")
		)
		(pad "1" smd rect
			(at -0.2667 0 270)
			(size 0.3048 0.381)
			(layers "F.Cu" "F.Mask" "F.Paste")
			(net "P5E_CPU1_P3_TX_C_DN<13>")
		)
		(pad "2" smd rect
			(at 0.2667 0 270)
			(size 0.3048 0.381)
			(layers "F.Cu" "F.Mask" "F.Paste")
			(net "P5E_CPU1_P3_TX_DN<13>")
		)
	)
	(footprint ""
		(layer "F.Cu")
		(at 72.463914 -147.649692 180)
		(property "Reference" "PR148"
			(at 0 0 180)
			(layer "F.SilkS")
			(hide yes)
			(effects
				(font
					(size 1.27 1.27)
				)
			)
		)
		(property "Value" ""
			(at 0 0 180)
			(layer "F.Fab")
			(effects
				(font
					(size 1.27 1.27)
				)
			)
		)
		(duplicate_pad_numbers_are_jumpers no)
		(fp_line
			(start 0.7874 0.4064)
			(end -0.7874 0.4064)
			(stroke
				(width 0.1524)
				(type default)
			)
			(layer "F.SilkS")
		)
		(fp_line
			(start 0.7874 -0.4064)
			(end 0.7874 0.4064)
			(stroke
				(width 0.1524)
				(type default)
			)
			(layer "F.SilkS")
		)
		(fp_line
			(start -0.7874 0.4064)
			(end -0.7874 -0.4064)
			(stroke
				(width 0.1524)
				(type default)
			)
			(layer "F.SilkS")
		)
		(fp_line
			(start -0.7874 -0.4064)
			(end 0.7874 -0.4064)
			(stroke
				(width 0.1524)
				(type default)
			)
			(layer "F.SilkS")
		)
		(fp_line
			(start 0.67945 0.3048)
			(end 0.120396 0.3048)
			(stroke
				(width 0.1)
				(type default)
			)
			(layer "F.Fab")
		)
		(fp_line
			(start 0.67945 -0.3048)
			(end 0.67945 0.3048)
			(stroke
				(width 0.1)
				(type default)
			)
			(layer "F.Fab")
		)
		(fp_line
			(start 0.12065 -0.2794)
			(end 0.12065 -0.3048)
			(stroke
				(width 0.1)
				(type default)
			)
			(layer "F.Fab")
		)
		(fp_line
			(start 0.12065 -0.3048)
			(end 0.67945 -0.3048)
			(stroke
				(width 0.1)
				(type default)
			)
			(layer "F.Fab")
		)
		(fp_line
			(start 0.120396 0.3048)
			(end 0.120396 0.2794)
			(stroke
				(width 0.1)
				(type default)
			)
			(layer "F.Fab")
		)
		(fp_line
			(start 0.120396 0.2794)
			(end -0.12065 0.2794)
			(stroke
				(width 0.1)
				(type default)
			)
			(layer "F.Fab")
		)
		(fp_line
			(start -0.12065 0.3048)
			(end -0.67945 0.3048)
			(stroke
				(width 0.1)
				(type default)
			)
			(layer "F.Fab")
		)
		(fp_line
			(start -0.12065 0.2794)
			(end -0.12065 0.3048)
			(stroke
				(width 0.1)
				(type default)
			)
			(layer "F.Fab")
		)
		(fp_line
			(start -0.12065 -0.2794)
			(end 0.12065 -0.2794)
			(stroke
				(width 0.1)
				(type default)
			)
			(layer "F.Fab")
		)
		(fp_line
			(start -0.12065 -0.305054)
			(end -0.12065 -0.2794)
			(stroke
				(width 0.1)
				(type default)
			)
			(layer "F.Fab")
		)
		(fp_line
			(start -0.67945 0.3048)
			(end -0.67945 -0.305054)
			(stroke
				(width 0.1)
				(type default)
			)
			(layer "F.Fab")
		)
		(fp_line
			(start -0.67945 -0.305054)
			(end -0.12065 -0.305054)
			(stroke
				(width 0.1)
				(type default)
			)
			(layer "F.Fab")
		)
		(pad "1" smd circle
			(at -0.40005 0 180)
			(size 0 0)
			(layers "F.Cu" "F.Mask" "F.Paste")
			(net "PVDD18_S5_P1_FB")
		)
		(pad "2" smd circle
			(at 0.40005 0 180)
			(size 0 0)
			(layers "F.Cu" "F.Mask" "F.Paste")
			(net "PVDD18_S5_P1_FB_RC")
		)
	)
	(footprint ""
		(layer "F.Cu")
		(at 71.235824 -18.932144 180)
		(property "Reference" "R1291"
			(at 0 0 180)
			(layer "F.SilkS")
			(hide yes)
			(effects
				(font
					(size 1.27 1.27)
				)
			)
		)
		(property "Value" ""
			(at 0 0 180)
			(layer "F.Fab")
			(effects
				(font
					(size 1.27 1.27)
				)
			)
		)
		(duplicate_pad_numbers_are_jumpers no)
		(fp_line
			(start 0.7874 0.4064)
			(end -0.7874 0.4064)
			(stroke
				(width 0.1524)
				(type default)
			)
			(layer "F.SilkS")
		)
		(fp_line
			(start 0.7874 -0.4064)
			(end 0.7874 0.4064)
			(stroke
				(width 0.1524)
				(type default)
			)
			(layer "F.SilkS")
		)
		(fp_line
			(start -0.7874 0.4064)
			(end -0.7874 -0.4064)
			(stroke
				(width 0.1524)
				(type default)
			)
			(layer "F.SilkS")
		)
		(fp_line
			(start -0.7874 -0.4064)
			(end 0.7874 -0.4064)
			(stroke
				(width 0.1524)
				(type default)
			)
			(layer "F.SilkS")
		)
		(fp_line
			(start 0.67945 0.3048)
			(end 0.120396 0.3048)
			(stroke
				(width 0.1)
				(type default)
			)
			(layer "F.Fab")
		)
		(fp_line
			(start 0.67945 -0.3048)
			(end 0.67945 0.3048)
			(stroke
				(width 0.1)
				(type default)
			)
			(layer "F.Fab")
		)
		(fp_line
			(start 0.12065 -0.2794)
			(end 0.12065 -0.3048)
			(stroke
				(width 0.1)
				(type default)
			)
			(layer "F.Fab")
		)
		(fp_line
			(start 0.12065 -0.3048)
			(end 0.67945 -0.3048)
			(stroke
				(width 0.1)
				(type default)
			)
			(layer "F.Fab")
		)
		(fp_line
			(start 0.120396 0.3048)
			(end 0.120396 0.2794)
			(stroke
				(width 0.1)
				(type default)
			)
			(layer "F.Fab")
		)
		(fp_line
			(start 0.120396 0.2794)
			(end -0.12065 0.2794)
			(stroke
				(width 0.1)
				(type default)
			)
			(layer "F.Fab")
		)
		(fp_line
			(start -0.12065 0.3048)
			(end -0.67945 0.3048)
			(stroke
				(width 0.1)
				(type default)
			)
			(layer "F.Fab")
		)
		(fp_line
			(start -0.12065 0.2794)
			(end -0.12065 0.3048)
			(stroke
				(width 0.1)
				(type default)
			)
			(layer "F.Fab")
		)
		(fp_line
			(start -0.12065 -0.2794)
			(end 0.12065 -0.2794)
			(stroke
				(width 0.1)
				(type default)
			)
			(layer "F.Fab")
		)
		(fp_line
			(start -0.12065 -0.305054)
			(end -0.12065 -0.2794)
			(stroke
				(width 0.1)
				(type default)
			)
			(layer "F.Fab")
		)
		(fp_line
			(start -0.67945 0.3048)
			(end -0.67945 -0.305054)
			(stroke
				(width 0.1)
				(type default)
			)
			(layer "F.Fab")
		)
		(fp_line
			(start -0.67945 -0.305054)
			(end -0.12065 -0.305054)
			(stroke
				(width 0.1)
				(type default)
			)
			(layer "F.Fab")
		)
		(pad "1" smd circle
			(at -0.40005 0 180)
			(size 0 0)
			(layers "F.Cu" "F.Mask" "F.Paste")
			(net "P12V_OCP_V3_2")
		)
		(pad "2" smd circle
			(at 0.40005 0 180)
			(size 0 0)
			(layers "F.Cu" "F.Mask" "F.Paste")
			(net "VSENSE_P12V_INA230_7_INP")
		)
	)
	(footprint ""
		(layer "F.Cu")
		(at 254.592836 -114.72545)
		(property "Reference" "R3730"
			(at 0 0 0)
			(layer "F.SilkS")
			(hide yes)
			(effects
				(font
					(size 1.27 1.27)
				)
			)
		)
		(property "Value" ""
			(at 0 0 0)
			(layer "F.Fab")
			(effects
				(font
					(size 1.27 1.27)
				)
			)
		)
		(duplicate_pad_numbers_are_jumpers no)
		(fp_line
			(start -0.7874 -0.4064)
			(end 0.7874 -0.4064)
			(stroke
				(width 0.1524)
				(type default)
			)
			(layer "F.SilkS")
		)
		(fp_line
			(start -0.7874 0.4064)
			(end -0.7874 -0.4064)
			(stroke
				(width 0.1524)
				(type default)
			)
			(layer "F.SilkS")
		)
		(fp_line
			(start 0.7874 -0.4064)
			(end 0.7874 0.4064)
			(stroke
				(width 0.1524)
				(type default)
			)
			(layer "F.SilkS")
		)
		(fp_line
			(start 0.7874 0.4064)
			(end -0.7874 0.4064)
			(stroke
				(width 0.1524)
				(type default)
			)
			(layer "F.SilkS")
		)
		(fp_line
			(start -0.67945 -0.305054)
			(end -0.12065 -0.305054)
			(stroke
				(width 0.1)
				(type default)
			)
			(layer "F.Fab")
		)
		(fp_line
			(start -0.67945 0.3048)
			(end -0.67945 -0.305054)
			(stroke
				(width 0.1)
				(type default)
			)
			(layer "F.Fab")
		)
		(fp_line
			(start -0.12065 -0.305054)
			(end -0.12065 -0.2794)
			(stroke
				(width 0.1)
				(type default)
			)
			(layer "F.Fab")
		)
		(fp_line
			(start -0.12065 -0.2794)
			(end 0.12065 -0.2794)
			(stroke
				(width 0.1)
				(type default)
			)
			(layer "F.Fab")
		)
		(fp_line
			(start -0.12065 0.2794)
			(end -0.12065 0.3048)
			(stroke
				(width 0.1)
				(type default)
			)
			(layer "F.Fab")
		)
		(fp_line
			(start -0.12065 0.3048)
			(end -0.67945 0.3048)
			(stroke
				(width 0.1)
				(type default)
			)
			(layer "F.Fab")
		)
		(fp_line
			(start 0.120396 0.2794)
			(end -0.12065 0.2794)
			(stroke
				(width 0.1)
				(type default)
			)
			(layer "F.Fab")
		)
		(fp_line
			(start 0.120396 0.3048)
			(end 0.120396 0.2794)
			(stroke
				(width 0.1)
				(type default)
			)
			(layer "F.Fab")
		)
		(fp_line
			(start 0.12065 -0.3048)
			(end 0.67945 -0.3048)
			(stroke
				(width 0.1)
				(type default)
			)
			(layer "F.Fab")
		)
		(fp_line
			(start 0.12065 -0.2794)
			(end 0.12065 -0.3048)
			(stroke
				(width 0.1)
				(type default)
			)
			(layer "F.Fab")
		)
		(fp_line
			(start 0.67945 -0.3048)
			(end 0.67945 0.3048)
			(stroke
				(width 0.1)
				(type default)
			)
			(layer "F.Fab")
		)
		(fp_line
			(start 0.67945 0.3048)
			(end 0.120396 0.3048)
			(stroke
				(width 0.1)
				(type default)
			)
			(layer "F.Fab")
		)
		(pad "1" smd circle
			(at -0.40005 0)
			(size 0 0)
			(layers "F.Cu" "F.Mask" "F.Paste")
			(net "P3V3_AUX")
		)
		(pad "2" smd circle
			(at 0.40005 0)
			(size 0 0)
			(layers "F.Cu" "F.Mask" "F.Paste")
			(net "SMB_LM75_2_3V3AUX_SDA")
		)
	)
	(footprint ""
		(layer "F.Cu")
		(at 127.705104 -52.14239)
		(property "Reference" "R1625"
			(at 0 0 0)
			(layer "F.SilkS")
			(hide yes)
			(effects
				(font
					(size 1.27 1.27)
				)
			)
		)
		(property "Value" ""
			(at 0 0 0)
			(layer "F.Fab")
			(effects
				(font
					(size 1.27 1.27)
				)
			)
		)
		(duplicate_pad_numbers_are_jumpers no)
		(fp_line
			(start -0.7874 -0.4064)
			(end 0.7874 -0.4064)
			(stroke
				(width 0.1524)
				(type default)
			)
			(layer "F.SilkS")
		)
		(fp_line
			(start -0.7874 0.4064)
			(end -0.7874 -0.4064)
			(stroke
				(width 0.1524)
				(type default)
			)
			(layer "F.SilkS")
		)
		(fp_line
			(start 0.7874 -0.4064)
			(end 0.7874 0.4064)
			(stroke
				(width 0.1524)
				(type default)
			)
			(layer "F.SilkS")
		)
		(fp_line
			(start 0.7874 0.4064)
			(end -0.7874 0.4064)
			(stroke
				(width 0.1524)
				(type default)
			)
			(layer "F.SilkS")
		)
		(fp_line
			(start -0.67945 -0.305054)
			(end -0.12065 -0.305054)
			(stroke
				(width 0.1)
				(type default)
			)
			(layer "F.Fab")
		)
		(fp_line
			(start -0.67945 0.3048)
			(end -0.67945 -0.305054)
			(stroke
				(width 0.1)
				(type default)
			)
			(layer "F.Fab")
		)
		(fp_line
			(start -0.12065 -0.305054)
			(end -0.12065 -0.2794)
			(stroke
				(width 0.1)
				(type default)
			)
			(layer "F.Fab")
		)
		(fp_line
			(start -0.12065 -0.2794)
			(end 0.12065 -0.2794)
			(stroke
				(width 0.1)
				(type default)
			)
			(layer "F.Fab")
		)
		(fp_line
			(start -0.12065 0.2794)
			(end -0.12065 0.3048)
			(stroke
				(width 0.1)
				(type default)
			)
			(layer "F.Fab")
		)
		(fp_line
			(start -0.12065 0.3048)
			(end -0.67945 0.3048)
			(stroke
				(width 0.1)
				(type default)
			)
			(layer "F.Fab")
		)
		(fp_line
			(start 0.120396 0.2794)
			(end -0.12065 0.2794)
			(stroke
				(width 0.1)
				(type default)
			)
			(layer "F.Fab")
		)
		(fp_line
			(start 0.120396 0.3048)
			(end 0.120396 0.2794)
			(stroke
				(width 0.1)
				(type default)
			)
			(layer "F.Fab")
		)
		(fp_line
			(start 0.12065 -0.3048)
			(end 0.67945 -0.3048)
			(stroke
				(width 0.1)
				(type default)
			)
			(layer "F.Fab")
		)
		(fp_line
			(start 0.12065 -0.2794)
			(end 0.12065 -0.3048)
			(stroke
				(width 0.1)
				(type default)
			)
			(layer "F.Fab")
		)
		(fp_line
			(start 0.67945 -0.3048)
			(end 0.67945 0.3048)
			(stroke
				(width 0.1)
				(type default)
			)
			(layer "F.Fab")
		)
		(fp_line
			(start 0.67945 0.3048)
			(end 0.120396 0.3048)
			(stroke
				(width 0.1)
				(type default)
			)
			(layer "F.Fab")
		)
		(pad "1" smd circle
			(at -0.40005 0)
			(size 0 0)
			(layers "F.Cu" "F.Mask" "F.Paste")
			(net "JTAG_TDI_R")
		)
		(pad "2" smd circle
			(at 0.40005 0)
			(size 0 0)
			(layers "F.Cu" "F.Mask" "F.Paste")
			(net "JTAG_TDI")
		)
	)
	(footprint ""
		(layer "F.Cu")
		(at 69.10451 -340.211664)
		(property "Reference" "PR263"
			(at 0 0 0)
			(layer "F.SilkS")
			(hide yes)
			(effects
				(font
					(size 1.27 1.27)
				)
			)
		)
		(property "Value" ""
			(at 0 0 0)
			(layer "F.Fab")
			(effects
				(font
					(size 1.27 1.27)
				)
			)
		)
		(duplicate_pad_numbers_are_jumpers no)
		(fp_line
			(start -0.7874 -0.4064)
			(end 0.7874 -0.4064)
			(stroke
				(width 0.1524)
				(type default)
			)
			(layer "F.SilkS")
		)
		(fp_line
			(start -0.7874 0.4064)
			(end -0.7874 -0.4064)
			(stroke
				(width 0.1524)
				(type default)
			)
			(layer "F.SilkS")
		)
		(fp_line
			(start 0.7874 -0.4064)
			(end 0.7874 0.4064)
			(stroke
				(width 0.1524)
				(type default)
			)
			(layer "F.SilkS")
		)
		(fp_line
			(start 0.7874 0.4064)
			(end -0.7874 0.4064)
			(stroke
				(width 0.1524)
				(type default)
			)
			(layer "F.SilkS")
		)
		(fp_line
			(start -0.67945 -0.305054)
			(end -0.12065 -0.305054)
			(stroke
				(width 0.1)
				(type default)
			)
			(layer "F.Fab")
		)
		(fp_line
			(start -0.67945 0.3048)
			(end -0.67945 -0.305054)
			(stroke
				(width 0.1)
				(type default)
			)
			(layer "F.Fab")
		)
		(fp_line
			(start -0.12065 -0.305054)
			(end -0.12065 -0.2794)
			(stroke
				(width 0.1)
				(type default)
			)
			(layer "F.Fab")
		)
		(fp_line
			(start -0.12065 -0.2794)
			(end 0.12065 -0.2794)
			(stroke
				(width 0.1)
				(type default)
			)
			(layer "F.Fab")
		)
		(fp_line
			(start -0.12065 0.2794)
			(end -0.12065 0.3048)
			(stroke
				(width 0.1)
				(type default)
			)
			(layer "F.Fab")
		)
		(fp_line
			(start -0.12065 0.3048)
			(end -0.67945 0.3048)
			(stroke
				(width 0.1)
				(type default)
			)
			(layer "F.Fab")
		)
		(fp_line
			(start 0.120396 0.2794)
			(end -0.12065 0.2794)
			(stroke
				(width 0.1)
				(type default)
			)
			(layer "F.Fab")
		)
		(fp_line
			(start 0.120396 0.3048)
			(end 0.120396 0.2794)
			(stroke
				(width 0.1)
				(type default)
			)
			(layer "F.Fab")
		)
		(fp_line
			(start 0.12065 -0.3048)
			(end 0.67945 -0.3048)
			(stroke
				(width 0.1)
				(type default)
			)
			(layer "F.Fab")
		)
		(fp_line
			(start 0.12065 -0.2794)
			(end 0.12065 -0.3048)
			(stroke
				(width 0.1)
				(type default)
			)
			(layer "F.Fab")
		)
		(fp_line
			(start 0.67945 -0.3048)
			(end 0.67945 0.3048)
			(stroke
				(width 0.1)
				(type default)
			)
			(layer "F.Fab")
		)
		(fp_line
			(start 0.67945 0.3048)
			(end 0.120396 0.3048)
			(stroke
				(width 0.1)
				(type default)
			)
			(layer "F.Fab")
		)
		(pad "1" smd circle
			(at -0.40005 0)
			(size 0 0)
			(layers "F.Cu" "F.Mask" "F.Paste")
			(net "PVDDCR_CPU1_P1_LSET3")
		)
		(pad "2" smd circle
			(at 0.40005 0)
			(size 0 0)
			(layers "F.Cu" "F.Mask" "F.Paste")
			(net "GND")
		)
	)
)
